FILE_TYPE=LIBRARY_PARTS;
primitive 'PXE1110B','PXE1110B_QFN';
  pin
    'DNC'<0>:
      PIN_NUMBER='(1)';
      PINUSE='NC';
      NO_LOAD_CHECK='Both';
      NO_IO_CHECK='Both';
      NO_ASSERT_CHECK='TRUE';
      NO_DIR_CHECK='TRUE';
      ALLOW_CONNECT='TRUE';
    'DNC'<1>:
      PIN_NUMBER='(2)';
      PINUSE='NC';
      NO_LOAD_CHECK='Both';
      NO_IO_CHECK='Both';
      NO_ASSERT_CHECK='TRUE';
      NO_DIR_CHECK='TRUE';
      ALLOW_CONNECT='TRUE';
    'BPWM1':
      PIN_NUMBER='(3)';
      OUTPUT_LOAD='(1.0,-1.0)';
    'DNC'<2>:
      PIN_NUMBER='(4)';
      PINUSE='NC';
      NO_LOAD_CHECK='Both';
      NO_IO_CHECK='Both';
      NO_ASSERT_CHECK='TRUE';
      NO_DIR_CHECK='TRUE';
      ALLOW_CONNECT='TRUE';
    'APWM1':
      PIN_NUMBER='(5)';
      OUTPUT_LOAD='(1.0,-1.0)';
    'SDA':
      PIN_NUMBER='(6)';
      BIDIRECTIONAL='TRUE';
      INPUT_LOAD='(-0.01,0.01)';
      OUTPUT_LOAD='(1.0,-1.0)';
    'SCL':
      PIN_NUMBER='(7)';
      BIDIRECTIONAL='TRUE';
      INPUT_LOAD='(-0.01,0.01)';
      OUTPUT_LOAD='(1.0,-1.0)';
    'RESET_N':
      PIN_NUMBER='(8)';
      INPUT_LOAD='(-0.01,0.01)';
    'AVRRDY':
      PIN_NUMBER='(9)';
      OUTPUT_LOAD='(1.0,-1.0)';
    'AVREN':
      PIN_NUMBER='(10)';
      INPUT_LOAD='(-0.01,0.01)';
    'VRHOT_N':
      PIN_NUMBER='(11)';
      OUTPUT_LOAD='(1.0,-1.0)';
    'PINALRT_N':
      PIN_NUMBER='(12)';
      OUTPUT_LOAD='(1.0,-1.0)';
    'MP0':
      PIN_NUMBER='(13)';
      BIDIRECTIONAL='TRUE';
      INPUT_LOAD='(-0.01,0.01)';
      OUTPUT_LOAD='(1.0,-1.0)';
    'MP1':
      PIN_NUMBER='(14)';
      BIDIRECTIONAL='TRUE';
      INPUT_LOAD='(-0.01,0.01)';
      OUTPUT_LOAD='(1.0,-1.0)';
    'VCLK':
      PIN_NUMBER='(15)';
      INPUT_LOAD='(-0.01,0.01)';
    'VDIO':
      PIN_NUMBER='(16)';
      BIDIRECTIONAL='TRUE';
      INPUT_LOAD='(-0.01,0.01)';
      OUTPUT_LOAD='(1.0,-1.0)';
    'VALRT_N':
      PIN_NUMBER='(17)';
      OUTPUT_LOAD='(1.0,-1.0)';
    'MP2':
      PIN_NUMBER='(18)';
      OUTPUT_LOAD='(1.0,-1.0)';
    'AVSEN':
      PIN_NUMBER='(19)';
      INPUT_LOAD='(-0.01,0.01)';
    'AVREF':
      PIN_NUMBER='(20)';
      INPUT_LOAD='(-0.01,0.01)';
    'AIREF1':
      PIN_NUMBER='(21)';
      INPUT_LOAD='(-0.01,0.01)';
    'AISEN1':
      PIN_NUMBER='(22)';
      INPUT_LOAD='(-0.01,0.01)';
    'GND'<1>:
      PIN_NUMBER='(23)';
      PINUSE='GROUND';
      NO_LOAD_CHECK='Both';
      NO_IO_CHECK='Both';
      NO_ASSERT_CHECK='TRUE';
      NO_DIR_CHECK='TRUE';
      ALLOW_CONNECT='TRUE';
    'DNC'<3>:
      PIN_NUMBER='(24)';
      PINUSE='NC';
      NO_LOAD_CHECK='Both';
      NO_IO_CHECK='Both';
      NO_ASSERT_CHECK='TRUE';
      NO_DIR_CHECK='TRUE';
      ALLOW_CONNECT='TRUE';
    'BIREF1':
      PIN_NUMBER='(25)';
      INPUT_LOAD='(-0.01,0.01)';
    'BISEN1':
      PIN_NUMBER='(26)';
      INPUT_LOAD='(-0.01,0.01)';
    'GND'<0>:
      PIN_NUMBER='(27)';
      PINUSE='GROUND';
      NO_LOAD_CHECK='Both';
      NO_IO_CHECK='Both';
      NO_ASSERT_CHECK='TRUE';
      NO_DIR_CHECK='TRUE';
      ALLOW_CONNECT='TRUE';
    'DNC'<4>:
      PIN_NUMBER='(28)';
      PINUSE='NC';
      NO_LOAD_CHECK='Both';
      NO_IO_CHECK='Both';
      NO_ASSERT_CHECK='TRUE';
      NO_DIR_CHECK='TRUE';
      ALLOW_CONNECT='TRUE';
    'BVSEN':
      PIN_NUMBER='(29)';
      INPUT_LOAD='(-0.01,0.01)';
    'BVREF':
      PIN_NUMBER='(30)';
      INPUT_LOAD='(-0.01,0.01)';
    'MP3':
      PIN_NUMBER='(31)';
      BIDIRECTIONAL='TRUE';
      INPUT_LOAD='(-0.01,0.01)';
      OUTPUT_LOAD='(1.0,-1.0)';
    'MP4':
      PIN_NUMBER='(32)';
      BIDIRECTIONAL='TRUE';
      INPUT_LOAD='(-0.01,0.01)';
      OUTPUT_LOAD='(1.0,-1.0)';
    'XADDR2':
      PIN_NUMBER='(33)';
      INPUT_LOAD='(-0.01,0.01)';
    'BTSEN':
      PIN_NUMBER='(34)';
      INPUT_LOAD='(-0.01,0.01)';
    'ATSEN':
      PIN_NUMBER='(35)';
      INPUT_LOAD='(-0.01,0.01)';
    'XADDR1':
      PIN_NUMBER='(36)';
      INPUT_LOAD='(-0.01,0.01)';
    'VINSEN':
      PIN_NUMBER='(37)';
      INPUT_LOAD='(-0.01,0.01)';
    'IINSEN':
      PIN_NUMBER='(38)';
      INPUT_LOAD='(-0.01,0.01)';
    'VDD':
      PIN_NUMBER='(39)';
      PINUSE='POWER';
      NO_LOAD_CHECK='Both';
      NO_IO_CHECK='Both';
      NO_ASSERT_CHECK='TRUE';
      NO_DIR_CHECK='TRUE';
      ALLOW_CONNECT='TRUE';
    'VD12':
      PIN_NUMBER='(40)';
      PINUSE='POWER';
      NO_LOAD_CHECK='Both';
      NO_IO_CHECK='Both';
      NO_ASSERT_CHECK='TRUE';
      NO_DIR_CHECK='TRUE';
      ALLOW_CONNECT='TRUE';
    'THPAD':
      PIN_NUMBER='(41)';
      PINUSE='GROUND';
      NO_LOAD_CHECK='Both';
      NO_IO_CHECK='Both';
      NO_ASSERT_CHECK='TRUE';
      NO_DIR_CHECK='TRUE';
      ALLOW_CONNECT='TRUE';
  end_pin;
  body
    PART_NAME='PXE1110B';
    PHYS_DES_PREFIX='EU';
  end_body;
end_primitive;

END.
